(kicad_pcb
	(version 20260206)
	(generator "pcbnew")
	(generator_version "10.0")
	(general
		(thickness 1.6)
		(legacy_teardrops no)
	)
	(paper "A4")
	(title_block
		(title "03242023_DA0F0TMBIJ0_F0T_Motherboard_J_brd_V01_OCP.brd")
		(comment 1 "Grand Teton / footprints 1547-1553 of 6105")
	)
	(layers
		(0 "F.Cu" signal "TOP")
		(4 "In1.Cu" signal "GND")
		(6 "In2.Cu" signal "IN1")
		(8 "In3.Cu" signal "GND1")
		(10 "In4.Cu" signal "IN2")
		(12 "In5.Cu" signal "GND2")
		(14 "In6.Cu" signal "IN3")
		(16 "In7.Cu" signal "GND3")
		(18 "In8.Cu" signal "VCC")
		(20 "In9.Cu" signal "VCC1")
		(22 "In10.Cu" signal "GND4")
		(24 "In11.Cu" signal "IN4")
		(26 "In12.Cu" signal "GND5")
		(28 "In13.Cu" signal "IN5")
		(30 "In14.Cu" signal "GND6")
		(32 "In15.Cu" signal "IN6")
		(34 "In16.Cu" signal "GND7")
		(2 "B.Cu" signal "BOTTOM")
		(9 "F.Adhes" user "F.Adhesive")
		(11 "B.Adhes" user "B.Adhesive")
		(13 "F.Paste" user "Package Geometry/Pastemask Top")
		(15 "B.Paste" user "Package Geometry/Pastemask Bottom")
		(5 "F.SilkS" user "Ref Des/Silkscreen Top")
		(7 "B.SilkS" user "Ref Des/Silkscreen Bottom")
		(1 "F.Mask" user "Board Geometry/Soldermask Top")
		(3 "B.Mask" user "Board Geometry/Soldermask Bottom")
		(17 "Dwgs.User" user "User.Drawings")
		(19 "Cmts.User" user "User.Comments")
		(21 "Eco1.User" user "User.Eco1")
		(23 "Eco2.User" user "User.Eco2")
		(25 "Edge.Cuts" user "Board Geometry/Outline")
		(27 "Margin" user)
		(31 "F.CrtYd" user "Package Geometry/Place Bound Top")
		(29 "B.CrtYd" user "Package Geometry/Place Bound Bottom")
		(35 "F.Fab" user "Ref Des/Assembly Top")
		(33 "B.Fab" user "Ref Des/Assembly Bottom")
	)
	(footprint ""
		(layer "F.Cu")
		(at 46.350428 -99.840034)
		(property "Reference" "C2045"
			(at 0 0 0)
			(layer "F.SilkS")
			(hide yes)
			(effects
				(font
					(size 1.27 1.27)
				)
			)
		)
		(property "Value" ""
			(at 0 0 0)
			(layer "F.Fab")
			(effects
				(font
					(size 1.27 1.27)
				)
			)
		)
		(duplicate_pad_numbers_are_jumpers no)
		(fp_line
			(start -0.7874 -0.4064)
			(end 0.7874 -0.4064)
			(stroke
				(width 0.1524)
				(type default)
			)
			(layer "F.SilkS")
		)
		(fp_line
			(start -0.7874 0.4064)
			(end -0.7874 -0.4064)
			(stroke
				(width 0.1524)
				(type default)
			)
			(layer "F.SilkS")
		)
		(fp_line
			(start 0.7874 -0.4064)
			(end 0.7874 0.4064)
			(stroke
				(width 0.1524)
				(type default)
			)
			(layer "F.SilkS")
		)
		(fp_line
			(start 0.7874 0.4064)
			(end -0.7874 0.4064)
			(stroke
				(width 0.1524)
				(type default)
			)
			(layer "F.SilkS")
		)
		(fp_line
			(start -0.67945 -0.305054)
			(end -0.12065 -0.305054)
			(stroke
				(width 0.1)
				(type default)
			)
			(layer "F.Fab")
		)
		(fp_line
			(start -0.67945 0.3048)
			(end -0.67945 -0.305054)
			(stroke
				(width 0.1)
				(type default)
			)
			(layer "F.Fab")
		)
		(fp_line
			(start -0.12065 -0.305054)
			(end -0.12065 -0.2794)
			(stroke
				(width 0.1)
				(type default)
			)
			(layer "F.Fab")
		)
		(fp_line
			(start -0.12065 -0.2794)
			(end 0.12065 -0.2794)
			(stroke
				(width 0.1)
				(type default)
			)
			(layer "F.Fab")
		)
		(fp_line
			(start -0.12065 0.2794)
			(end -0.12065 0.3048)
			(stroke
				(width 0.1)
				(type default)
			)
			(layer "F.Fab")
		)
		(fp_line
			(start -0.12065 0.3048)
			(end -0.67945 0.3048)
			(stroke
				(width 0.1)
				(type default)
			)
			(layer "F.Fab")
		)
		(fp_line
			(start 0.120396 0.2794)
			(end -0.12065 0.2794)
			(stroke
				(width 0.1)
				(type default)
			)
			(layer "F.Fab")
		)
		(fp_line
			(start 0.120396 0.3048)
			(end 0.120396 0.2794)
			(stroke
				(width 0.1)
				(type default)
			)
			(layer "F.Fab")
		)
		(fp_line
			(start 0.12065 -0.3048)
			(end 0.67945 -0.3048)
			(stroke
				(width 0.1)
				(type default)
			)
			(layer "F.Fab")
		)
		(fp_line
			(start 0.12065 -0.2794)
			(end 0.12065 -0.3048)
			(stroke
				(width 0.1)
				(type default)
			)
			(layer "F.Fab")
		)
		(fp_line
			(start 0.67945 -0.3048)
			(end 0.67945 0.3048)
			(stroke
				(width 0.1)
				(type default)
			)
			(layer "F.Fab")
		)
		(fp_line
			(start 0.67945 0.3048)
			(end 0.120396 0.3048)
			(stroke
				(width 0.1)
				(type default)
			)
			(layer "F.Fab")
		)
		(pad "1" smd circle
			(at -0.40005 0)
			(size 0 0)
			(layers "F.Cu" "F.Mask" "F.Paste")
			(net "P3V3_PDB_AUX_ADC_MAM")
		)
		(pad "2" smd circle
			(at 0.40005 0)
			(size 0 0)
			(layers "F.Cu" "F.Mask" "F.Paste")
			(net "GND")
		)
	)
	(footprint ""
		(layer "F.Cu")
		(at 320.190622 -58.283348)
		(property "Reference" "R617"
			(at 0 0 0)
			(layer "F.SilkS")
			(hide yes)
			(effects
				(font
					(size 1.27 1.27)
				)
			)
		)
		(property "Value" ""
			(at 0 0 0)
			(layer "F.Fab")
			(effects
				(font
					(size 1.27 1.27)
				)
			)
		)
		(duplicate_pad_numbers_are_jumpers no)
		(fp_line
			(start -0.7874 -0.4064)
			(end 0.7874 -0.4064)
			(stroke
				(width 0.1524)
				(type default)
			)
			(layer "F.SilkS")
		)
		(fp_line
			(start -0.7874 0.4064)
			(end -0.7874 -0.4064)
			(stroke
				(width 0.1524)
				(type default)
			)
			(layer "F.SilkS")
		)
		(fp_line
			(start 0.7874 -0.4064)
			(end 0.7874 0.4064)
			(stroke
				(width 0.1524)
				(type default)
			)
			(layer "F.SilkS")
		)
		(fp_line
			(start 0.7874 0.4064)
			(end -0.7874 0.4064)
			(stroke
				(width 0.1524)
				(type default)
			)
			(layer "F.SilkS")
		)
		(fp_line
			(start -0.67945 -0.305054)
			(end -0.12065 -0.305054)
			(stroke
				(width 0.1)
				(type default)
			)
			(layer "F.Fab")
		)
		(fp_line
			(start -0.67945 0.3048)
			(end -0.67945 -0.305054)
			(stroke
				(width 0.1)
				(type default)
			)
			(layer "F.Fab")
		)
		(fp_line
			(start -0.12065 -0.305054)
			(end -0.12065 -0.2794)
			(stroke
				(width 0.1)
				(type default)
			)
			(layer "F.Fab")
		)
		(fp_line
			(start -0.12065 -0.2794)
			(end 0.12065 -0.2794)
			(stroke
				(width 0.1)
				(type default)
			)
			(layer "F.Fab")
		)
		(fp_line
			(start -0.12065 0.2794)
			(end -0.12065 0.3048)
			(stroke
				(width 0.1)
				(type default)
			)
			(layer "F.Fab")
		)
		(fp_line
			(start -0.12065 0.3048)
			(end -0.67945 0.3048)
			(stroke
				(width 0.1)
				(type default)
			)
			(layer "F.Fab")
		)
		(fp_line
			(start 0.120396 0.2794)
			(end -0.12065 0.2794)
			(stroke
				(width 0.1)
				(type default)
			)
			(layer "F.Fab")
		)
		(fp_line
			(start 0.120396 0.3048)
			(end 0.120396 0.2794)
			(stroke
				(width 0.1)
				(type default)
			)
			(layer "F.Fab")
		)
		(fp_line
			(start 0.12065 -0.3048)
			(end 0.67945 -0.3048)
			(stroke
				(width 0.1)
				(type default)
			)
			(layer "F.Fab")
		)
		(fp_line
			(start 0.12065 -0.2794)
			(end 0.12065 -0.3048)
			(stroke
				(width 0.1)
				(type default)
			)
			(layer "F.Fab")
		)
		(fp_line
			(start 0.67945 -0.3048)
			(end 0.67945 0.3048)
			(stroke
				(width 0.1)
				(type default)
			)
			(layer "F.Fab")
		)
		(fp_line
			(start 0.67945 0.3048)
			(end 0.120396 0.3048)
			(stroke
				(width 0.1)
				(type default)
			)
			(layer "F.Fab")
		)
		(pad "1" smd circle
			(at -0.40005 0)
			(size 0 0)
			(layers "F.Cu" "F.Mask" "F.Paste")
			(net "P3V3_AUX")
		)
		(pad "2" smd circle
			(at 0.40005 0)
			(size 0 0)
			(layers "F.Cu" "F.Mask" "F.Paste")
			(net "FM_PCH_IO_EXPANDER")
		)
	)
	(footprint ""
		(layer "F.Cu")
		(at 39.263574 -387.340856 -90)
		(property "Reference" "C2358"
			(at 0 0 270)
			(layer "F.SilkS")
			(hide yes)
			(effects
				(font
					(size 1.27 1.27)
				)
			)
		)
		(property "Value" ""
			(at 0 0 270)
			(layer "F.Fab")
			(effects
				(font
					(size 1.27 1.27)
				)
			)
		)
		(duplicate_pad_numbers_are_jumpers no)
		(fp_line
			(start -0.7874 0.4064)
			(end -0.7874 -0.4064)
			(stroke
				(width 0.1524)
				(type default)
			)
			(layer "F.SilkS")
		)
		(fp_line
			(start 0.7874 0.4064)
			(end -0.7874 0.4064)
			(stroke
				(width 0.1524)
				(type default)
			)
			(layer "F.SilkS")
		)
		(fp_line
			(start -0.7874 -0.4064)
			(end 0.7874 -0.4064)
			(stroke
				(width 0.1524)
				(type default)
			)
			(layer "F.SilkS")
		)
		(fp_line
			(start 0.7874 -0.4064)
			(end 0.7874 0.4064)
			(stroke
				(width 0.1524)
				(type default)
			)
			(layer "F.SilkS")
		)
		(fp_line
			(start -0.67945 0.3048)
			(end -0.67945 -0.305054)
			(stroke
				(width 0.1)
				(type default)
			)
			(layer "F.Fab")
		)
		(fp_line
			(start -0.12065 0.3048)
			(end -0.67945 0.3048)
			(stroke
				(width 0.1)
				(type default)
			)
			(layer "F.Fab")
		)
		(fp_line
			(start 0.120396 0.3048)
			(end 0.120396 0.2794)
			(stroke
				(width 0.1)
				(type default)
			)
			(layer "F.Fab")
		)
		(fp_line
			(start 0.67945 0.3048)
			(end 0.120396 0.3048)
			(stroke
				(width 0.1)
				(type default)
			)
			(layer "F.Fab")
		)
		(fp_line
			(start -0.12065 0.2794)
			(end -0.12065 0.3048)
			(stroke
				(width 0.1)
				(type default)
			)
			(layer "F.Fab")
		)
		(fp_line
			(start 0.120396 0.2794)
			(end -0.12065 0.2794)
			(stroke
				(width 0.1)
				(type default)
			)
			(layer "F.Fab")
		)
		(fp_line
			(start -0.12065 -0.2794)
			(end 0.12065 -0.2794)
			(stroke
				(width 0.1)
				(type default)
			)
			(layer "F.Fab")
		)
		(fp_line
			(start 0.12065 -0.2794)
			(end 0.12065 -0.3048)
			(stroke
				(width 0.1)
				(type default)
			)
			(layer "F.Fab")
		)
		(fp_line
			(start 0.12065 -0.3048)
			(end 0.67945 -0.3048)
			(stroke
				(width 0.1)
				(type default)
			)
			(layer "F.Fab")
		)
		(fp_line
			(start 0.67945 -0.3048)
			(end 0.67945 0.3048)
			(stroke
				(width 0.1)
				(type default)
			)
			(layer "F.Fab")
		)
		(fp_line
			(start -0.67945 -0.305054)
			(end -0.12065 -0.305054)
			(stroke
				(width 0.1)
				(type default)
			)
			(layer "F.Fab")
		)
		(fp_line
			(start -0.12065 -0.305054)
			(end -0.12065 -0.2794)
			(stroke
				(width 0.1)
				(type default)
			)
			(layer "F.Fab")
		)
		(pad "1" smd circle
			(at -0.40005 0 270)
			(size 0 0)
			(layers "F.Cu" "F.Mask" "F.Paste")
			(net "P2E_BUF2_VDD")
		)
		(pad "2" smd circle
			(at 0.40005 0 270)
			(size 0 0)
			(layers "F.Cu" "F.Mask" "F.Paste")
			(net "GND")
		)
	)
	(footprint ""
		(layer "F.Cu")
		(at 312.443622 -35.84194 180)
		(property "Reference" "R1582"
			(at 0 0 180)
			(layer "F.SilkS")
			(hide yes)
			(effects
				(font
					(size 1.27 1.27)
				)
			)
		)
		(property "Value" ""
			(at 0 0 180)
			(layer "F.Fab")
			(effects
				(font
					(size 1.27 1.27)
				)
			)
		)
		(duplicate_pad_numbers_are_jumpers no)
		(fp_line
			(start 0.7874 0.4064)
			(end -0.7874 0.4064)
			(stroke
				(width 0.1524)
				(type default)
			)
			(layer "F.SilkS")
		)
		(fp_line
			(start 0.7874 -0.4064)
			(end 0.7874 0.4064)
			(stroke
				(width 0.1524)
				(type default)
			)
			(layer "F.SilkS")
		)
		(fp_line
			(start -0.7874 0.4064)
			(end -0.7874 -0.4064)
			(stroke
				(width 0.1524)
				(type default)
			)
			(layer "F.SilkS")
		)
		(fp_line
			(start -0.7874 -0.4064)
			(end 0.7874 -0.4064)
			(stroke
				(width 0.1524)
				(type default)
			)
			(layer "F.SilkS")
		)
		(fp_line
			(start 0.67945 0.3048)
			(end 0.120396 0.3048)
			(stroke
				(width 0.1)
				(type default)
			)
			(layer "F.Fab")
		)
		(fp_line
			(start 0.67945 -0.3048)
			(end 0.67945 0.3048)
			(stroke
				(width 0.1)
				(type default)
			)
			(layer "F.Fab")
		)
		(fp_line
			(start 0.12065 -0.2794)
			(end 0.12065 -0.3048)
			(stroke
				(width 0.1)
				(type default)
			)
			(layer "F.Fab")
		)
		(fp_line
			(start 0.12065 -0.3048)
			(end 0.67945 -0.3048)
			(stroke
				(width 0.1)
				(type default)
			)
			(layer "F.Fab")
		)
		(fp_line
			(start 0.120396 0.3048)
			(end 0.120396 0.2794)
			(stroke
				(width 0.1)
				(type default)
			)
			(layer "F.Fab")
		)
		(fp_line
			(start 0.120396 0.2794)
			(end -0.12065 0.2794)
			(stroke
				(width 0.1)
				(type default)
			)
			(layer "F.Fab")
		)
		(fp_line
			(start -0.12065 0.3048)
			(end -0.67945 0.3048)
			(stroke
				(width 0.1)
				(type default)
			)
			(layer "F.Fab")
		)
		(fp_line
			(start -0.12065 0.2794)
			(end -0.12065 0.3048)
			(stroke
				(width 0.1)
				(type default)
			)
			(layer "F.Fab")
		)
		(fp_line
			(start -0.12065 -0.2794)
			(end 0.12065 -0.2794)
			(stroke
				(width 0.1)
				(type default)
			)
			(layer "F.Fab")
		)
		(fp_line
			(start -0.12065 -0.305054)
			(end -0.12065 -0.2794)
			(stroke
				(width 0.1)
				(type default)
			)
			(layer "F.Fab")
		)
		(fp_line
			(start -0.67945 0.3048)
			(end -0.67945 -0.305054)
			(stroke
				(width 0.1)
				(type default)
			)
			(layer "F.Fab")
		)
		(fp_line
			(start -0.67945 -0.305054)
			(end -0.12065 -0.305054)
			(stroke
				(width 0.1)
				(type default)
			)
			(layer "F.Fab")
		)
		(pad "1" smd circle
			(at -0.40005 0 180)
			(size 0 0)
			(layers "F.Cu" "F.Mask" "F.Paste")
			(net "PU_SMB_PCH_PLD_3V3AUX_SDA")
		)
		(pad "2" smd circle
			(at 0.40005 0 180)
			(size 0 0)
			(layers "F.Cu" "F.Mask" "F.Paste")
			(net "P3V3_AUX")
		)
	)
	(footprint ""
		(layer "F.Cu")
		(at 393.724384 -17.612614 90)
		(property "Reference" "C841"
			(at 0 0 90)
			(layer "F.SilkS")
			(hide yes)
			(effects
				(font
					(size 1.27 1.27)
				)
			)
		)
		(property "Value" ""
			(at 0 0 90)
			(layer "F.Fab")
			(effects
				(font
					(size 1.27 1.27)
				)
			)
		)
		(duplicate_pad_numbers_are_jumpers no)
		(fp_line
			(start 0.299974 -0.150114)
			(end 0.299974 0.150114)
			(stroke
				(width 0.1)
				(type default)
			)
			(layer "F.Fab")
		)
		(fp_line
			(start -0.299974 -0.150114)
			(end 0.299974 -0.150114)
			(stroke
				(width 0.1)
				(type default)
			)
			(layer "F.Fab")
		)
		(fp_line
			(start 0.299974 0.150114)
			(end -0.299974 0.150114)
			(stroke
				(width 0.1)
				(type default)
			)
			(layer "F.Fab")
		)
		(fp_line
			(start -0.299974 0.150114)
			(end -0.299974 -0.150114)
			(stroke
				(width 0.1)
				(type default)
			)
			(layer "F.Fab")
		)
		(pad "1" smd rect
			(at -0.2667 0 90)
			(size 0.3048 0.381)
			(layers "F.Cu" "F.Mask" "F.Paste")
			(net "P5E_CPU0_PE1_TX_C_DP<14>")
		)
		(pad "2" smd rect
			(at 0.2667 0 90)
			(size 0.3048 0.381)
			(layers "F.Cu" "F.Mask" "F.Paste")
			(net "P5E_CPU0_PE1_TX_DP<14>")
		)
	)
	(footprint ""
		(layer "F.Cu")
		(at 186.74588 -130.266948 -90)
		(property "Reference" "R287"
			(at 0 0 270)
			(layer "F.SilkS")
			(hide yes)
			(effects
				(font
					(size 1.27 1.27)
				)
			)
		)
		(property "Value" ""
			(at 0 0 270)
			(layer "F.Fab")
			(effects
				(font
					(size 1.27 1.27)
				)
			)
		)
		(duplicate_pad_numbers_are_jumpers no)
		(fp_line
			(start -0.7874 0.4064)
			(end -0.7874 -0.4064)
			(stroke
				(width 0.1524)
				(type default)
			)
			(layer "F.SilkS")
		)
		(fp_line
			(start 0.7874 0.4064)
			(end -0.7874 0.4064)
			(stroke
				(width 0.1524)
				(type default)
			)
			(layer "F.SilkS")
		)
		(fp_line
			(start -0.7874 -0.4064)
			(end 0.7874 -0.4064)
			(stroke
				(width 0.1524)
				(type default)
			)
			(layer "F.SilkS")
		)
		(fp_line
			(start 0.7874 -0.4064)
			(end 0.7874 0.4064)
			(stroke
				(width 0.1524)
				(type default)
			)
			(layer "F.SilkS")
		)
		(fp_line
			(start -0.67945 0.3048)
			(end -0.67945 -0.305054)
			(stroke
				(width 0.1)
				(type default)
			)
			(layer "F.Fab")
		)
		(fp_line
			(start -0.12065 0.3048)
			(end -0.67945 0.3048)
			(stroke
				(width 0.1)
				(type default)
			)
			(layer "F.Fab")
		)
		(fp_line
			(start 0.120396 0.3048)
			(end 0.120396 0.2794)
			(stroke
				(width 0.1)
				(type default)
			)
			(layer "F.Fab")
		)
		(fp_line
			(start 0.67945 0.3048)
			(end 0.120396 0.3048)
			(stroke
				(width 0.1)
				(type default)
			)
			(layer "F.Fab")
		)
		(fp_line
			(start -0.12065 0.2794)
			(end -0.12065 0.3048)
			(stroke
				(width 0.1)
				(type default)
			)
			(layer "F.Fab")
		)
		(fp_line
			(start 0.120396 0.2794)
			(end -0.12065 0.2794)
			(stroke
				(width 0.1)
				(type default)
			)
			(layer "F.Fab")
		)
		(fp_line
			(start -0.12065 -0.2794)
			(end 0.12065 -0.2794)
			(stroke
				(width 0.1)
				(type default)
			)
			(layer "F.Fab")
		)
		(fp_line
			(start 0.12065 -0.2794)
			(end 0.12065 -0.3048)
			(stroke
				(width 0.1)
				(type default)
			)
			(layer "F.Fab")
		)
		(fp_line
			(start 0.12065 -0.3048)
			(end 0.67945 -0.3048)
			(stroke
				(width 0.1)
				(type default)
			)
			(layer "F.Fab")
		)
		(fp_line
			(start 0.67945 -0.3048)
			(end 0.67945 0.3048)
			(stroke
				(width 0.1)
				(type default)
			)
			(layer "F.Fab")
		)
		(fp_line
			(start -0.67945 -0.305054)
			(end -0.12065 -0.305054)
			(stroke
				(width 0.1)
				(type default)
			)
			(layer "F.Fab")
		)
		(fp_line
			(start -0.12065 -0.305054)
			(end -0.12065 -0.2794)
			(stroke
				(width 0.1)
				(type default)
			)
			(layer "F.Fab")
		)
		(pad "1" smd circle
			(at -0.40005 0 270)
			(size 0 0)
			(layers "F.Cu" "F.Mask" "F.Paste")
			(net "P3V3_AUX")
		)
		(pad "2" smd circle
			(at 0.40005 0 270)
			(size 0 0)
			(layers "F.Cu" "F.Mask" "F.Paste")
			(net "FM_CPU0_PROC_ID1")
		)
	)
	(footprint ""
		(layer "F.Cu")
		(at 312.42 -23.9268)
		(property "Reference" "R4789"
			(at 0 0 0)
			(layer "F.SilkS")
			(hide yes)
			(effects
				(font
					(size 1.27 1.27)
				)
			)
		)
		(property "Value" ""
			(at 0 0 0)
			(layer "F.Fab")
			(effects
				(font
					(size 1.27 1.27)
				)
			)
		)
		(duplicate_pad_numbers_are_jumpers no)
		(fp_line
			(start -0.7874 -0.4064)
			(end 0.7874 -0.4064)
			(stroke
				(width 0.1524)
				(type default)
			)
			(layer "F.SilkS")
		)
		(fp_line
			(start -0.7874 0.4064)
			(end -0.7874 -0.4064)
			(stroke
				(width 0.1524)
				(type default)
			)
			(layer "F.SilkS")
		)
		(fp_line
			(start 0.7874 -0.4064)
			(end 0.7874 0.4064)
			(stroke
				(width 0.1524)
				(type default)
			)
			(layer "F.SilkS")
		)
		(fp_line
			(start 0.7874 0.4064)
			(end -0.7874 0.4064)
			(stroke
				(width 0.1524)
				(type default)
			)
			(layer "F.SilkS")
		)
		(fp_line
			(start -0.67945 -0.305054)
			(end -0.12065 -0.305054)
			(stroke
				(width 0.1)
				(type default)
			)
			(layer "F.Fab")
		)
		(fp_line
			(start -0.67945 0.3048)
			(end -0.67945 -0.305054)
			(stroke
				(width 0.1)
				(type default)
			)
			(layer "F.Fab")
		)
		(fp_line
			(start -0.12065 -0.305054)
			(end -0.12065 -0.2794)
			(stroke
				(width 0.1)
				(type default)
			)
			(layer "F.Fab")
		)
		(fp_line
			(start -0.12065 -0.2794)
			(end 0.12065 -0.2794)
			(stroke
				(width 0.1)
				(type default)
			)
			(layer "F.Fab")
		)
		(fp_line
			(start -0.12065 0.2794)
			(end -0.12065 0.3048)
			(stroke
				(width 0.1)
				(type default)
			)
			(layer "F.Fab")
		)
		(fp_line
			(start -0.12065 0.3048)
			(end -0.67945 0.3048)
			(stroke
				(width 0.1)
				(type default)
			)
			(layer "F.Fab")
		)
		(fp_line
			(start 0.120396 0.2794)
			(end -0.12065 0.2794)
			(stroke
				(width 0.1)
				(type default)
			)
			(layer "F.Fab")
		)
		(fp_line
			(start 0.120396 0.3048)
			(end 0.120396 0.2794)
			(stroke
				(width 0.1)
				(type default)
			)
			(layer "F.Fab")
		)
		(fp_line
			(start 0.12065 -0.3048)
			(end 0.67945 -0.3048)
			(stroke
				(width 0.1)
				(type default)
			)
			(layer "F.Fab")
		)
		(fp_line
			(start 0.12065 -0.2794)
			(end 0.12065 -0.3048)
			(stroke
				(width 0.1)
				(type default)
			)
			(layer "F.Fab")
		)
		(fp_line
			(start 0.67945 -0.3048)
			(end 0.67945 0.3048)
			(stroke
				(width 0.1)
				(type default)
			)
			(layer "F.Fab")
		)
		(fp_line
			(start 0.67945 0.3048)
			(end 0.120396 0.3048)
			(stroke
				(width 0.1)
				(type default)
			)
			(layer "F.Fab")
		)
		(pad "1" smd circle
			(at -0.40005 0)
			(size 0 0)
			(layers "F.Cu" "F.Mask" "F.Paste")
			(net "P3V3_AUX")
		)
		(pad "2" smd circle
			(at 0.40005 0)
			(size 0 0)
			(layers "F.Cu" "F.Mask" "F.Paste")
			(net "PWRGD_DSW_PWROK")
		)
	)
)
